# T6G (Grand Teton) — schematic netlist excerpt (pin names and nets, part order shuffled) for the footprints in the layout excerpt that follows; sources: Cadence DE-HDL packaged netlist, KiCad conversion of 04192023_DAF0TMB3IC0_F0TG_MB_C_brd_V02_OCP.brd

R1342  Q_RES  10K 1% CHIP  pkg 0402LF  page 171 : A = FW_RECOVERY_R ; B = GND
R3530  Q_RES  4.7K 5% CHIP  pkg 0402LF  page 148 : A = P3V3_E1S_0 ; B = SMB_E1S_3V3AUX_ISO_SCL_R

(kicad_pcb
	(version 20260206)
	(generator "pcbnew")
	(generator_version "10.0")
	(general
		(thickness 1.6)
		(legacy_teardrops no)
	)
	(paper "A4")
	(title_block
		(title "04192023_DAF0TMB3IC0_F0TG_MB_C_brd_V02_OCP.brd")
		(comment 1 "Grand Teton / footprints 758-759 of 8354")
	)
	(layers
		(0 "F.Cu" signal "TOP")
		(4 "In1.Cu" signal "GND")
		(6 "In2.Cu" signal "IN1")
		(8 "In3.Cu" signal "GND1")
		(10 "In4.Cu" signal "IN2")
		(12 "In5.Cu" signal "GND2")
		(14 "In6.Cu" signal "IN3")
		(16 "In7.Cu" signal "GND3")
		(18 "In8.Cu" signal "VCC")
		(20 "In9.Cu" signal "VCC1")
		(22 "In10.Cu" signal "GND4")
		(24 "In11.Cu" signal "IN4")
		(26 "In12.Cu" signal "GND5")
		(28 "In13.Cu" signal "IN5")
		(30 "In14.Cu" signal "GND6")
		(32 "In15.Cu" signal "IN6")
		(34 "In16.Cu" signal "GND7")
		(2 "B.Cu" signal "BOTTOM")
		(9 "F.Adhes" user "F.Adhesive")
		(11 "B.Adhes" user "B.Adhesive")
		(13 "F.Paste" user "Package Geometry/Pastemask Top")
		(15 "B.Paste" user "Package Geometry/Pastemask Bottom")
		(5 "F.SilkS" user "Ref Des/Silkscreen Top")
		(7 "B.SilkS" user "Ref Des/Silkscreen Bottom")
		(1 "F.Mask" user "Board Geometry/Soldermask Top")
		(3 "B.Mask" user "Board Geometry/Soldermask Bottom")
		(17 "Dwgs.User" user "User.Drawings")
		(19 "Cmts.User" user "User.Comments")
		(21 "Eco1.User" user "User.Eco1")
		(23 "Eco2.User" user "User.Eco2")
		(25 "Edge.Cuts" user "Board Geometry/Outline")
		(27 "Margin" user)
		(31 "F.CrtYd" user "Package Geometry/Place Bound Top")
		(29 "B.CrtYd" user "Package Geometry/Place Bound Bottom")
		(35 "F.Fab" user "Ref Des/Assembly Top")
		(33 "B.Fab" user "Ref Des/Assembly Bottom")
	)
	(footprint ""
		(layer "F.Cu")
		(at 221.67088 -43.525948 180)
		(property "Reference" "R3530"
			(at 0 0 180)
			(layer "F.SilkS")
			(hide yes)
			(effects
				(font
					(size 1.27 1.27)
				)
			)
		)
		(property "Value" ""
			(at 0 0 180)
			(layer "F.Fab")
			(effects
				(font
					(size 1.27 1.27)
				)
			)
		)
		(duplicate_pad_numbers_are_jumpers no)
		(fp_line
			(start 0.7874 0.4064)
			(end -0.7874 0.4064)
			(stroke
				(width 0.1524)
				(type default)
			)
			(layer "F.SilkS")
		)
		(fp_line
			(start 0.7874 -0.4064)
			(end 0.7874 0.4064)
			(stroke
				(width 0.1524)
				(type default)
			)
			(layer "F.SilkS")
		)
		(fp_line
			(start -0.7874 0.4064)
			(end -0.7874 -0.4064)
			(stroke
				(width 0.1524)
				(type default)
			)
			(layer "F.SilkS")
		)
		(fp_line
			(start -0.7874 -0.4064)
			(end 0.7874 -0.4064)
			(stroke
				(width 0.1524)
				(type default)
			)
			(layer "F.SilkS")
		)
		(fp_line
			(start 0.67945 0.3048)
			(end 0.120396 0.3048)
			(stroke
				(width 0.1)
				(type default)
			)
			(layer "F.Fab")
		)
		(fp_line
			(start 0.67945 -0.3048)
			(end 0.67945 0.3048)
			(stroke
				(width 0.1)
				(type default)
			)
			(layer "F.Fab")
		)
		(fp_line
			(start 0.12065 -0.2794)
			(end 0.12065 -0.3048)
			(stroke
				(width 0.1)
				(type default)
			)
			(layer "F.Fab")
		)
		(fp_line
			(start 0.12065 -0.3048)
			(end 0.67945 -0.3048)
			(stroke
				(width 0.1)
				(type default)
			)
			(layer "F.Fab")
		)
		(fp_line
			(start 0.120396 0.3048)
			(end 0.120396 0.2794)
			(stroke
				(width 0.1)
				(type default)
			)
			(layer "F.Fab")
		)
		(fp_line
			(start 0.120396 0.2794)
			(end -0.12065 0.2794)
			(stroke
				(width 0.1)
				(type default)
			)
			(layer "F.Fab")
		)
		(fp_line
			(start -0.12065 0.3048)
			(end -0.67945 0.3048)
			(stroke
				(width 0.1)
				(type default)
			)
			(layer "F.Fab")
		)
		(fp_line
			(start -0.12065 0.2794)
			(end -0.12065 0.3048)
			(stroke
				(width 0.1)
				(type default)
			)
			(layer "F.Fab")
		)
		(fp_line
			(start -0.12065 -0.2794)
			(end 0.12065 -0.2794)
			(stroke
				(width 0.1)
				(type default)
			)
			(layer "F.Fab")
		)
		(fp_line
			(start -0.12065 -0.305054)
			(end -0.12065 -0.2794)
			(stroke
				(width 0.1)
				(type default)
			)
			(layer "F.Fab")
		)
		(fp_line
			(start -0.67945 0.3048)
			(end -0.67945 -0.305054)
			(stroke
				(width 0.1)
				(type default)
			)
			(layer "F.Fab")
		)
		(fp_line
			(start -0.67945 -0.305054)
			(end -0.12065 -0.305054)
			(stroke
				(width 0.1)
				(type default)
			)
			(layer "F.Fab")
		)
		(pad "1" smd circle
			(at -0.40005 0 180)
			(size 0 0)
			(layers "F.Cu" "F.Mask" "F.Paste")
			(net "P3V3_E1S_0")
		)
		(pad "2" smd circle
			(at 0.40005 0 180)
			(size 0 0)
			(layers "F.Cu" "F.Mask" "F.Paste")
			(net "SMB_E1S_3V3AUX_ISO_SCL_R")
		)
	)
	(footprint ""
		(layer "F.Cu")
		(at 312.499248 -23.52929 -90)
		(property "Reference" "R1342"
			(at 0 0 270)
			(layer "F.SilkS")
			(hide yes)
			(effects
				(font
					(size 1.27 1.27)
				)
			)
		)
		(property "Value" ""
			(at 0 0 270)
			(layer "F.Fab")
			(effects
				(font
					(size 1.27 1.27)
				)
			)
		)
		(duplicate_pad_numbers_are_jumpers no)
		(fp_line
			(start -0.7874 0.4064)
			(end -0.7874 -0.4064)
			(stroke
				(width 0.1524)
				(type default)
			)
			(layer "F.SilkS")
		)
		(fp_line
			(start 0.7874 0.4064)
			(end -0.7874 0.4064)
			(stroke
				(width 0.1524)
				(type default)
			)
			(layer "F.SilkS")
		)
		(fp_line
			(start -0.7874 -0.4064)
			(end 0.7874 -0.4064)
			(stroke
				(width 0.1524)
				(type default)
			)
			(layer "F.SilkS")
		)
		(fp_line
			(start 0.7874 -0.4064)
			(end 0.7874 0.4064)
			(stroke
				(width 0.1524)
				(type default)
			)
			(layer "F.SilkS")
		)
		(fp_line
			(start -0.67945 0.3048)
			(end -0.67945 -0.305054)
			(stroke
				(width 0.1)
				(type default)
			)
			(layer "F.Fab")
		)
		(fp_line
			(start -0.12065 0.3048)
			(end -0.67945 0.3048)
			(stroke
				(width 0.1)
				(type default)
			)
			(layer "F.Fab")
		)
		(fp_line
			(start 0.120396 0.3048)
			(end 0.120396 0.2794)
			(stroke
				(width 0.1)
				(type default)
			)
			(layer "F.Fab")
		)
		(fp_line
			(start 0.67945 0.3048)
			(end 0.120396 0.3048)
			(stroke
				(width 0.1)
				(type default)
			)
			(layer "F.Fab")
		)
		(fp_line
			(start -0.12065 0.2794)
			(end -0.12065 0.3048)
			(stroke
				(width 0.1)
				(type default)
			)
			(layer "F.Fab")
		)
		(fp_line
			(start 0.120396 0.2794)
			(end -0.12065 0.2794)
			(stroke
				(width 0.1)
				(type default)
			)
			(layer "F.Fab")
		)
		(fp_line
			(start -0.12065 -0.2794)
			(end 0.12065 -0.2794)
			(stroke
				(width 0.1)
				(type default)
			)
			(layer "F.Fab")
		)
		(fp_line
			(start 0.12065 -0.2794)
			(end 0.12065 -0.3048)
			(stroke
				(width 0.1)
				(type default)
			)
			(layer "F.Fab")
		)
		(fp_line
			(start 0.12065 -0.3048)
			(end 0.67945 -0.3048)
			(stroke
				(width 0.1)
				(type default)
			)
			(layer "F.Fab")
		)
		(fp_line
			(start 0.67945 -0.3048)
			(end 0.67945 0.3048)
			(stroke
				(width 0.1)
				(type default)
			)
			(layer "F.Fab")
		)
		(fp_line
			(start -0.67945 -0.305054)
			(end -0.12065 -0.305054)
			(stroke
				(width 0.1)
				(type default)
			)
			(layer "F.Fab")
		)
		(fp_line
			(start -0.12065 -0.305054)
			(end -0.12065 -0.2794)
			(stroke
				(width 0.1)
				(type default)
			)
			(layer "F.Fab")
		)
		(pad "1" smd circle
			(at -0.40005 0 270)
			(size 0 0)
			(layers "F.Cu" "F.Mask" "F.Paste")
			(net "FW_RECOVERY_R")
		)
		(pad "2" smd circle
			(at 0.40005 0 270)
			(size 0 0)
			(layers "F.Cu" "F.Mask" "F.Paste")
			(net "GND")
		)
	)
)
